(kicad_pcb
	(version 20260206)
	(generator "pcbnew")
	(generator_version "10.0")
	(general
		(thickness 1.6)
		(legacy_teardrops no)
	)
	(paper "A4")
	(title_block
		(title "12092022_DA0F0TFB6D0_F0T_FAN_BOARD_MP5048_D_brd_v02_OCP.brd")
		(comment 1 "Grand Teton / footprints 244-249 of 924")
	)
	(layers
		(0 "F.Cu" signal "TOP")
		(4 "In1.Cu" signal "GND")
		(6 "In2.Cu" signal "IN1")
		(8 "In3.Cu" signal "IN2")
		(10 "In4.Cu" signal "GND1")
		(2 "B.Cu" signal "BOTTOM")
		(9 "F.Adhes" user "F.Adhesive")
		(11 "B.Adhes" user "B.Adhesive")
		(13 "F.Paste" user "Package Geometry/Pastemask Top")
		(15 "B.Paste" user "Package Geometry/Pastemask Bottom")
		(5 "F.SilkS" user "Ref Des/Silkscreen Top")
		(7 "B.SilkS" user "Ref Des/Silkscreen Bottom")
		(1 "F.Mask" user "Board Geometry/Soldermask Top")
		(3 "B.Mask" user "Board Geometry/Soldermask Bottom")
		(17 "Dwgs.User" user "User.Drawings")
		(19 "Cmts.User" user "User.Comments")
		(21 "Eco1.User" user "User.Eco1")
		(23 "Eco2.User" user "User.Eco2")
		(25 "Edge.Cuts" user "Board Geometry/Outline")
		(27 "Margin" user)
		(31 "F.CrtYd" user "Package Geometry/Place Bound Top")
		(29 "B.CrtYd" user "Package Geometry/Place Bound Bottom")
		(35 "F.Fab" user "Ref Des/Assembly Top")
		(33 "B.Fab" user "Ref Des/Assembly Bottom")
	)
	(footprint ""
		(layer "F.Cu")
		(at 28.956 -160.02 90)
		(property "Reference" "R4877"
			(at 0 0 90)
			(layer "F.SilkS")
			(hide yes)
			(effects
				(font
					(size 1.27 1.27)
				)
			)
		)
		(property "Value" ""
			(at 0 0 90)
			(layer "F.Fab")
			(effects
				(font
					(size 1.27 1.27)
				)
			)
		)
		(duplicate_pad_numbers_are_jumpers no)
		(fp_line
			(start 0.7874 -0.4064)
			(end 0.7874 0.4064)
			(stroke
				(width 0.1524)
				(type default)
			)
			(layer "F.SilkS")
		)
		(fp_line
			(start -0.7874 -0.4064)
			(end 0.7874 -0.4064)
			(stroke
				(width 0.1524)
				(type default)
			)
			(layer "F.SilkS")
		)
		(fp_line
			(start 0.7874 0.4064)
			(end -0.7874 0.4064)
			(stroke
				(width 0.1524)
				(type default)
			)
			(layer "F.SilkS")
		)
		(fp_line
			(start -0.7874 0.4064)
			(end -0.7874 -0.4064)
			(stroke
				(width 0.1524)
				(type default)
			)
			(layer "F.SilkS")
		)
		(fp_line
			(start -0.12065 -0.305054)
			(end -0.12065 -0.2794)
			(stroke
				(width 0.1)
				(type default)
			)
			(layer "F.Fab")
		)
		(fp_line
			(start -0.67945 -0.305054)
			(end -0.12065 -0.305054)
			(stroke
				(width 0.1)
				(type default)
			)
			(layer "F.Fab")
		)
		(fp_line
			(start 0.67945 -0.3048)
			(end 0.67945 0.3048)
			(stroke
				(width 0.1)
				(type default)
			)
			(layer "F.Fab")
		)
		(fp_line
			(start 0.12065 -0.3048)
			(end 0.67945 -0.3048)
			(stroke
				(width 0.1)
				(type default)
			)
			(layer "F.Fab")
		)
		(fp_line
			(start 0.12065 -0.2794)
			(end 0.12065 -0.3048)
			(stroke
				(width 0.1)
				(type default)
			)
			(layer "F.Fab")
		)
		(fp_line
			(start -0.12065 -0.2794)
			(end 0.12065 -0.2794)
			(stroke
				(width 0.1)
				(type default)
			)
			(layer "F.Fab")
		)
		(fp_line
			(start 0.120396 0.2794)
			(end -0.12065 0.2794)
			(stroke
				(width 0.1)
				(type default)
			)
			(layer "F.Fab")
		)
		(fp_line
			(start -0.12065 0.2794)
			(end -0.12065 0.3048)
			(stroke
				(width 0.1)
				(type default)
			)
			(layer "F.Fab")
		)
		(fp_line
			(start 0.67945 0.3048)
			(end 0.120396 0.3048)
			(stroke
				(width 0.1)
				(type default)
			)
			(layer "F.Fab")
		)
		(fp_line
			(start 0.120396 0.3048)
			(end 0.120396 0.2794)
			(stroke
				(width 0.1)
				(type default)
			)
			(layer "F.Fab")
		)
		(fp_line
			(start -0.12065 0.3048)
			(end -0.67945 0.3048)
			(stroke
				(width 0.1)
				(type default)
			)
			(layer "F.Fab")
		)
		(fp_line
			(start -0.67945 0.3048)
			(end -0.67945 -0.305054)
			(stroke
				(width 0.1)
				(type default)
			)
			(layer "F.Fab")
		)
		(pad "1" smd circle
			(at -0.40005 0 90)
			(size 0 0)
			(layers "F.Cu" "F.Mask" "F.Paste")
			(net "SMB_FAN5_R_SCL")
		)
		(pad "2" smd circle
			(at 0.40005 0 90)
			(size 0 0)
			(layers "F.Cu" "F.Mask" "F.Paste")
			(net "SMB_FAN5_SCL")
		)
	)
	(footprint ""
		(layer "F.Cu")
		(at 17.907 -162.814 180)
		(property "Reference" "R5495"
			(at 0 0 180)
			(layer "F.SilkS")
			(hide yes)
			(effects
				(font
					(size 1.27 1.27)
				)
			)
		)
		(property "Value" ""
			(at 0 0 180)
			(layer "F.Fab")
			(effects
				(font
					(size 1.27 1.27)
				)
			)
		)
		(duplicate_pad_numbers_are_jumpers no)
		(fp_line
			(start 0.7874 0.4064)
			(end -0.7874 0.4064)
			(stroke
				(width 0.1524)
				(type default)
			)
			(layer "F.SilkS")
		)
		(fp_line
			(start 0.7874 -0.4064)
			(end 0.7874 0.4064)
			(stroke
				(width 0.1524)
				(type default)
			)
			(layer "F.SilkS")
		)
		(fp_line
			(start -0.7874 0.4064)
			(end -0.7874 -0.4064)
			(stroke
				(width 0.1524)
				(type default)
			)
			(layer "F.SilkS")
		)
		(fp_line
			(start -0.7874 -0.4064)
			(end 0.7874 -0.4064)
			(stroke
				(width 0.1524)
				(type default)
			)
			(layer "F.SilkS")
		)
		(fp_line
			(start 0.67945 0.3048)
			(end 0.120396 0.3048)
			(stroke
				(width 0.1)
				(type default)
			)
			(layer "F.Fab")
		)
		(fp_line
			(start 0.67945 -0.3048)
			(end 0.67945 0.3048)
			(stroke
				(width 0.1)
				(type default)
			)
			(layer "F.Fab")
		)
		(fp_line
			(start 0.12065 -0.2794)
			(end 0.12065 -0.3048)
			(stroke
				(width 0.1)
				(type default)
			)
			(layer "F.Fab")
		)
		(fp_line
			(start 0.12065 -0.3048)
			(end 0.67945 -0.3048)
			(stroke
				(width 0.1)
				(type default)
			)
			(layer "F.Fab")
		)
		(fp_line
			(start 0.120396 0.3048)
			(end 0.120396 0.2794)
			(stroke
				(width 0.1)
				(type default)
			)
			(layer "F.Fab")
		)
		(fp_line
			(start 0.120396 0.2794)
			(end -0.12065 0.2794)
			(stroke
				(width 0.1)
				(type default)
			)
			(layer "F.Fab")
		)
		(fp_line
			(start -0.12065 0.3048)
			(end -0.67945 0.3048)
			(stroke
				(width 0.1)
				(type default)
			)
			(layer "F.Fab")
		)
		(fp_line
			(start -0.12065 0.2794)
			(end -0.12065 0.3048)
			(stroke
				(width 0.1)
				(type default)
			)
			(layer "F.Fab")
		)
		(fp_line
			(start -0.12065 -0.2794)
			(end 0.12065 -0.2794)
			(stroke
				(width 0.1)
				(type default)
			)
			(layer "F.Fab")
		)
		(fp_line
			(start -0.12065 -0.305054)
			(end -0.12065 -0.2794)
			(stroke
				(width 0.1)
				(type default)
			)
			(layer "F.Fab")
		)
		(fp_line
			(start -0.67945 0.3048)
			(end -0.67945 -0.305054)
			(stroke
				(width 0.1)
				(type default)
			)
			(layer "F.Fab")
		)
		(fp_line
			(start -0.67945 -0.305054)
			(end -0.12065 -0.305054)
			(stroke
				(width 0.1)
				(type default)
			)
			(layer "F.Fab")
		)
		(pad "1" smd circle
			(at -0.40005 0 180)
			(size 0 0)
			(layers "F.Cu" "F.Mask" "F.Paste")
			(net "FAN_0_PRESENT_R_N")
		)
		(pad "2" smd circle
			(at 0.40005 0 180)
			(size 0 0)
			(layers "F.Cu" "F.Mask" "F.Paste")
			(net "FAN_0_PRESENT_N")
		)
	)
	(footprint ""
		(layer "F.Cu")
		(at 14.87805 -136.144)
		(property "Reference" "R5620"
			(at 0 0 0)
			(layer "F.SilkS")
			(hide yes)
			(effects
				(font
					(size 1.27 1.27)
				)
			)
		)
		(property "Value" ""
			(at 0 0 0)
			(layer "F.Fab")
			(effects
				(font
					(size 1.27 1.27)
				)
			)
		)
		(duplicate_pad_numbers_are_jumpers no)
		(fp_line
			(start -0.7874 -0.4064)
			(end 0.7874 -0.4064)
			(stroke
				(width 0.1524)
				(type default)
			)
			(layer "F.SilkS")
		)
		(fp_line
			(start -0.7874 0.4064)
			(end -0.7874 -0.4064)
			(stroke
				(width 0.1524)
				(type default)
			)
			(layer "F.SilkS")
		)
		(fp_line
			(start 0.7874 -0.4064)
			(end 0.7874 0.4064)
			(stroke
				(width 0.1524)
				(type default)
			)
			(layer "F.SilkS")
		)
		(fp_line
			(start 0.7874 0.4064)
			(end -0.7874 0.4064)
			(stroke
				(width 0.1524)
				(type default)
			)
			(layer "F.SilkS")
		)
		(fp_line
			(start -0.67945 -0.305054)
			(end -0.12065 -0.305054)
			(stroke
				(width 0.1)
				(type default)
			)
			(layer "F.Fab")
		)
		(fp_line
			(start -0.67945 0.3048)
			(end -0.67945 -0.305054)
			(stroke
				(width 0.1)
				(type default)
			)
			(layer "F.Fab")
		)
		(fp_line
			(start -0.12065 -0.305054)
			(end -0.12065 -0.2794)
			(stroke
				(width 0.1)
				(type default)
			)
			(layer "F.Fab")
		)
		(fp_line
			(start -0.12065 -0.2794)
			(end 0.12065 -0.2794)
			(stroke
				(width 0.1)
				(type default)
			)
			(layer "F.Fab")
		)
		(fp_line
			(start -0.12065 0.2794)
			(end -0.12065 0.3048)
			(stroke
				(width 0.1)
				(type default)
			)
			(layer "F.Fab")
		)
		(fp_line
			(start -0.12065 0.3048)
			(end -0.67945 0.3048)
			(stroke
				(width 0.1)
				(type default)
			)
			(layer "F.Fab")
		)
		(fp_line
			(start 0.120396 0.2794)
			(end -0.12065 0.2794)
			(stroke
				(width 0.1)
				(type default)
			)
			(layer "F.Fab")
		)
		(fp_line
			(start 0.120396 0.3048)
			(end 0.120396 0.2794)
			(stroke
				(width 0.1)
				(type default)
			)
			(layer "F.Fab")
		)
		(fp_line
			(start 0.12065 -0.3048)
			(end 0.67945 -0.3048)
			(stroke
				(width 0.1)
				(type default)
			)
			(layer "F.Fab")
		)
		(fp_line
			(start 0.12065 -0.2794)
			(end 0.12065 -0.3048)
			(stroke
				(width 0.1)
				(type default)
			)
			(layer "F.Fab")
		)
		(fp_line
			(start 0.67945 -0.3048)
			(end 0.67945 0.3048)
			(stroke
				(width 0.1)
				(type default)
			)
			(layer "F.Fab")
		)
		(fp_line
			(start 0.67945 0.3048)
			(end 0.120396 0.3048)
			(stroke
				(width 0.1)
				(type default)
			)
			(layer "F.Fab")
		)
		(pad "1" smd rect
			(at -0.40005 0 180)
			(size 0.4572 0.508)
			(layers "F.Cu" "F.Mask" "F.Paste")
			(net "FAN_7_TACH_OL")
		)
		(pad "2" smd rect
			(at 0.40005 0 180)
			(size 0.4572 0.508)
			(layers "F.Cu" "F.Mask" "F.Paste")
			(net "FAN_7_TACH_OL_R1")
		)
	)
	(footprint ""
		(layer "F.Cu")
		(at 22.225 -133.985 90)
		(property "Reference" "R4946"
			(at 0 0 90)
			(layer "F.SilkS")
			(hide yes)
			(effects
				(font
					(size 1.27 1.27)
				)
			)
		)
		(property "Value" ""
			(at 0 0 90)
			(layer "F.Fab")
			(effects
				(font
					(size 1.27 1.27)
				)
			)
		)
		(duplicate_pad_numbers_are_jumpers no)
		(fp_line
			(start 0.7874 -0.4064)
			(end 0.7874 0.4064)
			(stroke
				(width 0.1524)
				(type default)
			)
			(layer "F.SilkS")
		)
		(fp_line
			(start -0.7874 -0.4064)
			(end 0.7874 -0.4064)
			(stroke
				(width 0.1524)
				(type default)
			)
			(layer "F.SilkS")
		)
		(fp_line
			(start 0.7874 0.4064)
			(end -0.7874 0.4064)
			(stroke
				(width 0.1524)
				(type default)
			)
			(layer "F.SilkS")
		)
		(fp_line
			(start -0.7874 0.4064)
			(end -0.7874 -0.4064)
			(stroke
				(width 0.1524)
				(type default)
			)
			(layer "F.SilkS")
		)
		(fp_line
			(start -0.12065 -0.305054)
			(end -0.12065 -0.2794)
			(stroke
				(width 0.1)
				(type default)
			)
			(layer "F.Fab")
		)
		(fp_line
			(start -0.67945 -0.305054)
			(end -0.12065 -0.305054)
			(stroke
				(width 0.1)
				(type default)
			)
			(layer "F.Fab")
		)
		(fp_line
			(start 0.67945 -0.3048)
			(end 0.67945 0.3048)
			(stroke
				(width 0.1)
				(type default)
			)
			(layer "F.Fab")
		)
		(fp_line
			(start 0.12065 -0.3048)
			(end 0.67945 -0.3048)
			(stroke
				(width 0.1)
				(type default)
			)
			(layer "F.Fab")
		)
		(fp_line
			(start 0.12065 -0.2794)
			(end 0.12065 -0.3048)
			(stroke
				(width 0.1)
				(type default)
			)
			(layer "F.Fab")
		)
		(fp_line
			(start -0.12065 -0.2794)
			(end 0.12065 -0.2794)
			(stroke
				(width 0.1)
				(type default)
			)
			(layer "F.Fab")
		)
		(fp_line
			(start 0.120396 0.2794)
			(end -0.12065 0.2794)
			(stroke
				(width 0.1)
				(type default)
			)
			(layer "F.Fab")
		)
		(fp_line
			(start -0.12065 0.2794)
			(end -0.12065 0.3048)
			(stroke
				(width 0.1)
				(type default)
			)
			(layer "F.Fab")
		)
		(fp_line
			(start 0.67945 0.3048)
			(end 0.120396 0.3048)
			(stroke
				(width 0.1)
				(type default)
			)
			(layer "F.Fab")
		)
		(fp_line
			(start 0.120396 0.3048)
			(end 0.120396 0.2794)
			(stroke
				(width 0.1)
				(type default)
			)
			(layer "F.Fab")
		)
		(fp_line
			(start -0.12065 0.3048)
			(end -0.67945 0.3048)
			(stroke
				(width 0.1)
				(type default)
			)
			(layer "F.Fab")
		)
		(fp_line
			(start -0.67945 0.3048)
			(end -0.67945 -0.305054)
			(stroke
				(width 0.1)
				(type default)
			)
			(layer "F.Fab")
		)
		(pad "1" smd circle
			(at -0.40005 0 90)
			(size 0 0)
			(layers "F.Cu" "F.Mask" "F.Paste")
			(net "MAX31790_U330_SPIN_START")
		)
		(pad "2" smd circle
			(at 0.40005 0 90)
			(size 0 0)
			(layers "F.Cu" "F.Mask" "F.Paste")
			(net "P3V3_AUX")
		)
	)
	(footprint ""
		(layer "F.Cu")
		(at 17.399 -22.606 180)
		(property "Reference" "U342"
			(at 7.112 -0.15367 0)
			(unlocked yes)
			(layer "F.SilkS")
			(effects
				(font
					(size 0.7874 0.5842)
					(thickness 0.1524)
				)
				(justify left)
			)
		)
		(property "Value" ""
			(at 0 0 180)
			(layer "F.Fab")
			(effects
				(font
					(size 1.27 1.27)
				)
			)
		)
		(duplicate_pad_numbers_are_jumpers no)
		(fp_line
			(start 1.335278 1.100074)
			(end 1.335278 -1.100074)
			(stroke
				(width 0.1524)
				(type default)
			)
			(layer "F.SilkS")
		)
		(fp_line
			(start 1.335278 -1.100074)
			(end -1.335278 -1.100074)
			(stroke
				(width 0.1524)
				(type default)
			)
			(layer "F.SilkS")
		)
		(fp_line
			(start -1.335278 1.100074)
			(end 1.335278 1.100074)
			(stroke
				(width 0.1524)
				(type default)
			)
			(layer "F.SilkS")
		)
		(fp_line
			(start -1.335278 -1.100074)
			(end -1.335278 1.100074)
			(stroke
				(width 0.1524)
				(type default)
			)
			(layer "F.SilkS")
		)
		(fp_line
			(start 0.674878 1.100074)
			(end 0.674878 -1.100074)
			(stroke
				(width 0.1)
				(type default)
			)
			(layer "F.Fab")
		)
		(fp_line
			(start 0.674878 -1.100074)
			(end -0.674878 -1.100074)
			(stroke
				(width 0.1)
				(type default)
			)
			(layer "F.Fab")
		)
		(fp_line
			(start -0.674878 1.100074)
			(end 0.674878 1.100074)
			(stroke
				(width 0.1)
				(type default)
			)
			(layer "F.Fab")
		)
		(fp_line
			(start -0.674878 -1.100074)
			(end -0.674878 1.100074)
			(stroke
				(width 0.1)
				(type default)
			)
			(layer "F.Fab")
		)
		(pad "D" smd rect
			(at 0.8001 0 90)
			(size 0.6096 0.8128)
			(layers "F.Cu" "F.Mask" "F.Paste")
			(net "FAN_4_FAIL_LED_R_N")
		)
		(pad "G" smd rect
			(at -0.8001 -0.649986 90)
			(size 0.6096 0.8128)
			(layers "F.Cu" "F.Mask" "F.Paste")
			(net "FAN_4_FAIL_R_LED")
		)
		(pad "S" smd rect
			(at -0.8001 0.649986 90)
			(size 0.6096 0.8128)
			(layers "F.Cu" "F.Mask" "F.Paste")
			(net "GND")
		)
	)
	(footprint ""
		(layer "F.Cu")
		(at 15.621 -167.64)
		(property "Reference" "C58"
			(at 0 0 0)
			(layer "F.SilkS")
			(hide yes)
			(effects
				(font
					(size 1.27 1.27)
				)
			)
		)
		(property "Value" ""
			(at 0 0 0)
			(layer "F.Fab")
			(effects
				(font
					(size 1.27 1.27)
				)
			)
		)
		(duplicate_pad_numbers_are_jumpers no)
		(fp_line
			(start -0.7874 -0.4064)
			(end 0.7874 -0.4064)
			(stroke
				(width 0.1524)
				(type default)
			)
			(layer "F.SilkS")
		)
		(fp_line
			(start -0.7874 0.4064)
			(end -0.7874 -0.4064)
			(stroke
				(width 0.1524)
				(type default)
			)
			(layer "F.SilkS")
		)
		(fp_line
			(start 0.7874 -0.4064)
			(end 0.7874 0.4064)
			(stroke
				(width 0.1524)
				(type default)
			)
			(layer "F.SilkS")
		)
		(fp_line
			(start 0.7874 0.4064)
			(end -0.7874 0.4064)
			(stroke
				(width 0.1524)
				(type default)
			)
			(layer "F.SilkS")
		)
		(fp_line
			(start -0.67945 -0.305054)
			(end -0.12065 -0.305054)
			(stroke
				(width 0.1)
				(type default)
			)
			(layer "F.Fab")
		)
		(fp_line
			(start -0.67945 0.3048)
			(end -0.67945 -0.305054)
			(stroke
				(width 0.1)
				(type default)
			)
			(layer "F.Fab")
		)
		(fp_line
			(start -0.12065 -0.305054)
			(end -0.12065 -0.2794)
			(stroke
				(width 0.1)
				(type default)
			)
			(layer "F.Fab")
		)
		(fp_line
			(start -0.12065 -0.2794)
			(end 0.12065 -0.2794)
			(stroke
				(width 0.1)
				(type default)
			)
			(layer "F.Fab")
		)
		(fp_line
			(start -0.12065 0.2794)
			(end -0.12065 0.3048)
			(stroke
				(width 0.1)
				(type default)
			)
			(layer "F.Fab")
		)
		(fp_line
			(start -0.12065 0.3048)
			(end -0.67945 0.3048)
			(stroke
				(width 0.1)
				(type default)
			)
			(layer "F.Fab")
		)
		(fp_line
			(start 0.120396 0.2794)
			(end -0.12065 0.2794)
			(stroke
				(width 0.1)
				(type default)
			)
			(layer "F.Fab")
		)
		(fp_line
			(start 0.120396 0.3048)
			(end 0.120396 0.2794)
			(stroke
				(width 0.1)
				(type default)
			)
			(layer "F.Fab")
		)
		(fp_line
			(start 0.12065 -0.3048)
			(end 0.67945 -0.3048)
			(stroke
				(width 0.1)
				(type default)
			)
			(layer "F.Fab")
		)
		(fp_line
			(start 0.12065 -0.2794)
			(end 0.12065 -0.3048)
			(stroke
				(width 0.1)
				(type default)
			)
			(layer "F.Fab")
		)
		(fp_line
			(start 0.67945 -0.3048)
			(end 0.67945 0.3048)
			(stroke
				(width 0.1)
				(type default)
			)
			(layer "F.Fab")
		)
		(fp_line
			(start 0.67945 0.3048)
			(end 0.120396 0.3048)
			(stroke
				(width 0.1)
				(type default)
			)
			(layer "F.Fab")
		)
		(pad "1" smd circle
			(at -0.40005 0)
			(size 0 0)
			(layers "F.Cu" "F.Mask" "F.Paste")
			(net "FAN_3_PRESENT_N")
		)
		(pad "2" smd circle
			(at 0.40005 0)
			(size 0 0)
			(layers "F.Cu" "F.Mask" "F.Paste")
			(net "GND")
		)
	)
)
